# BASEBOARD_FAB2 (Tioga Pass) — schematic netlist excerpt (pin names and nets, part order shuffled) for the footprints in the layout excerpt that follows; sources: Cadence DE-HDL packaged netlist, KiCad conversion of Wiwynn_Tioga_Pass_MB.brd

C7P6  CAP  100UF 4V 20% X5R  pkg 0805  page 76 : A = PVCCMCP_CPU1 ; B = GND
R2T20  RES  0.0 5% CHIP  pkg 0402  page 93 : A = H_CPU1_ERR0_G_N ; B = H_CPU_ERR0_GTL_R_N
C2L18  CAP_A  0.01UF 25V 10% X7R  pkg 0402V  page 173 : A = SATA6G_PCH_PCIE_UP_SATA_RXN<4> ; B = SATA6G_P4_RX_C_DN

(kicad_pcb
	(version 20260206)
	(generator "pcbnew")
	(generator_version "10.0")
	(general
		(thickness 1.6)
		(legacy_teardrops no)
	)
	(paper "A4")
	(title_block
		(title "Wiwynn_Tioga_Pass_MB.brd")
		(comment 1 "Tioga Pass / footprints 2370-2372 of 4770")
	)
	(layers
		(0 "F.Cu" signal "TOP")
		(4 "In1.Cu" signal "L2GND")
		(6 "In2.Cu" signal "L3")
		(8 "In3.Cu" signal "L4GND")
		(10 "In4.Cu" signal "L5")
		(12 "In5.Cu" signal "L6GND")
		(14 "In6.Cu" signal "L7VCC")
		(16 "In7.Cu" signal "L8VCC")
		(18 "In8.Cu" signal "L9GND")
		(20 "In9.Cu" signal "L10")
		(22 "In10.Cu" signal "L11GND")
		(24 "In11.Cu" signal "L12")
		(26 "In12.Cu" signal "L13GND")
		(2 "B.Cu" signal "BOTTOM")
		(9 "F.Adhes" user "F.Adhesive")
		(11 "B.Adhes" user "B.Adhesive")
		(13 "F.Paste" user "Package Geometry/Pastemask Top")
		(15 "B.Paste" user "Package Geometry/Pastemask Bottom")
		(5 "F.SilkS" user "Ref Des/Silkscreen Top")
		(7 "B.SilkS" user "Ref Des/Silkscreen Bottom")
		(1 "F.Mask" user "Board Geometry/Soldermask Top")
		(3 "B.Mask" user "Board Geometry/Soldermask Bottom")
		(17 "Dwgs.User" user "User.Drawings")
		(19 "Cmts.User" user "User.Comments")
		(21 "Eco1.User" user "User.Eco1")
		(23 "Eco2.User" user "User.Eco2")
		(25 "Edge.Cuts" user "Board Geometry/Outline")
		(27 "Margin" user)
		(31 "F.CrtYd" user "Package Geometry/Place Bound Top")
		(29 "B.CrtYd" user "Package Geometry/Place Bound Bottom")
		(35 "F.Fab" user "Ref Des/Assembly Top")
		(33 "B.Fab" user "Ref Des/Assembly Bottom")
	)
	(footprint ""
		(layer "B.Cu")
		(at 410.464 -149.95652 90)
		(property "Reference" "C2L18"
			(at 0 0 90)
			(layer "B.SilkS")
			(hide yes)
			(effects
				(font
					(size 1.27 1.27)
				)
				(justify mirror)
			)
		)
		(property "Value" ""
			(at 0 0 90)
			(layer "B.Fab")
			(effects
				(font
					(size 1.27 1.27)
				)
				(justify mirror)
			)
		)
		(duplicate_pad_numbers_are_jumpers no)
		(fp_poly
			(pts
				(xy -0.3048 -0.1016) (xy -0.3048 0.9906) (xy 0.3048 0.9906) (xy 0.3048 -0.1016)
			)
			(stroke
				(width 0)
				(type default)
			)
			(fill no)
			(layer "B.CrtYd")
		)
		(fp_line
			(start 0.3048 -0.1016)
			(end 0.3048 0.9906)
			(stroke
				(width 0.1)
				(type default)
			)
			(layer "B.Fab")
		)
		(fp_line
			(start -0.3048 -0.1016)
			(end 0.3048 -0.1016)
			(stroke
				(width 0.1)
				(type default)
			)
			(layer "B.Fab")
		)
		(fp_line
			(start 0.3048 0.9906)
			(end -0.3048 0.9906)
			(stroke
				(width 0.1)
				(type default)
			)
			(layer "B.Fab")
		)
		(fp_line
			(start -0.3048 0.9906)
			(end -0.3048 -0.1016)
			(stroke
				(width 0.1)
				(type default)
			)
			(layer "B.Fab")
		)
		(pad "1" smd rect
			(at 0 0 270)
			(size 0.508 0.508)
			(layers "B.Cu" "B.Mask" "B.Paste")
			(net "SATA6G_PCH_PCIE_UP_SATA_RXN<4>")
		)
		(pad "2" smd rect
			(at 0 0.889 270)
			(size 0.508 0.508)
			(layers "B.Cu" "B.Mask" "B.Paste")
			(net "SATA6G_P4_RX_C_DN")
		)
		(zone
			(layer "B.Cu")
			(hatch none 0.5)
			(connect_pads
				(clearance 0)
			)
			(min_thickness 0.25)
			(keepout
				(tracks allowed)
				(vias not_allowed)
				(pads allowed)
				(copperpour not_allowed)
				(footprints allowed)
			)
			(placement
				(enabled no)
				(sheetname "")
			)
			(fill
				(thermal_gap 0.5)
				(thermal_bridge_width 0.5)
				(island_removal_mode 0)
			)
			(polygon
				(pts
					(xy 410.718 -150.21052) (xy 410.718 -149.70252) (xy 411.099 -149.70252) (xy 411.099 -150.21052)
				)
			)
		)
		(zone
			(layer "B.Cu")
			(hatch none 0.5)
			(connect_pads
				(clearance 0)
			)
			(min_thickness 0.25)
			(keepout
				(tracks not_allowed)
				(vias allowed)
				(pads allowed)
				(copperpour not_allowed)
				(footprints allowed)
			)
			(placement
				(enabled no)
				(sheetname "")
			)
			(fill
				(thermal_gap 0.5)
				(thermal_bridge_width 0.5)
				(island_removal_mode 0)
			)
			(polygon
				(pts
					(xy 411.099 -150.21052) (xy 411.099 -149.70252) (xy 410.718 -149.70252) (xy 410.718 -150.21052)
				)
			)
		)
	)
	(footprint ""
		(layer "B.Cu")
		(at 110.388654 -79.60614 180)
		(property "Reference" "C7P6"
			(at 0 0 0)
			(layer "B.SilkS")
			(hide yes)
			(effects
				(font
					(size 1.27 1.27)
				)
				(justify mirror)
			)
		)
		(property "Value" ""
			(at 0 0 0)
			(layer "B.Fab")
			(effects
				(font
					(size 1.27 1.27)
				)
				(justify mirror)
			)
		)
		(duplicate_pad_numbers_are_jumpers no)
		(fp_poly
			(pts
				(xy 0.7239 -0.2159) (xy -0.7239 -0.2159) (xy -0.7239 1.9939) (xy 0.7239 1.9939)
			)
			(stroke
				(width 0)
				(type default)
			)
			(fill no)
			(layer "B.CrtYd")
		)
		(fp_line
			(start 0.7239 1.9939)
			(end -0.7239 1.9939)
			(stroke
				(width 0.1)
				(type default)
			)
			(layer "B.Fab")
		)
		(fp_line
			(start 0.7239 -0.2159)
			(end 0.7239 1.9939)
			(stroke
				(width 0.1)
				(type default)
			)
			(layer "B.Fab")
		)
		(fp_line
			(start -0.7239 1.9939)
			(end -0.7239 -0.2159)
			(stroke
				(width 0.1)
				(type default)
			)
			(layer "B.Fab")
		)
		(fp_line
			(start -0.7239 -0.2159)
			(end 0.7239 -0.2159)
			(stroke
				(width 0.1)
				(type default)
			)
			(layer "B.Fab")
		)
		(pad "1" smd rect
			(at 0 0)
			(size 1.27 1.016)
			(layers "B.Cu" "B.Mask" "B.Paste")
			(net "PVCCMCP_CPU1")
		)
		(pad "2" smd rect
			(at 0 1.778)
			(size 1.27 1.016)
			(layers "B.Cu" "B.Mask" "B.Paste")
			(net "GND")
		)
		(zone
			(layer "B.Cu")
			(hatch none 0.5)
			(connect_pads
				(clearance 0)
			)
			(min_thickness 0.25)
			(keepout
				(tracks not_allowed)
				(vias allowed)
				(pads allowed)
				(copperpour not_allowed)
				(footprints allowed)
			)
			(placement
				(enabled no)
				(sheetname "")
			)
			(fill
				(thermal_gap 0.5)
				(thermal_bridge_width 0.5)
				(island_removal_mode 0)
			)
			(polygon
				(pts
					(xy 109.753654 -80.11414) (xy 111.023654 -80.11414) (xy 111.023654 -80.87614) (xy 109.753654 -80.87614)
				)
			)
		)
	)
	(footprint ""
		(layer "B.Cu")
		(at 375.062242 -40.662352 -90)
		(property "Reference" "R2T20"
			(at 0 0 90)
			(layer "B.SilkS")
			(hide yes)
			(effects
				(font
					(size 1.27 1.27)
				)
				(justify mirror)
			)
		)
		(property "Value" ""
			(at 0 0 90)
			(layer "B.Fab")
			(effects
				(font
					(size 1.27 1.27)
				)
				(justify mirror)
			)
		)
		(duplicate_pad_numbers_are_jumpers no)
		(fp_poly
			(pts
				(xy 0.2794 -0.1016) (xy -0.2794 -0.1016) (xy -0.2794 0.9906) (xy 0.2794 0.9906)
			)
			(stroke
				(width 0)
				(type default)
			)
			(fill no)
			(layer "B.CrtYd")
		)
		(fp_line
			(start -0.2794 0.9906)
			(end -0.2794 -0.1016)
			(stroke
				(width 0.1)
				(type default)
			)
			(layer "B.Fab")
		)
		(fp_line
			(start 0.2794 0.9906)
			(end -0.2794 0.9906)
			(stroke
				(width 0.1)
				(type default)
			)
			(layer "B.Fab")
		)
		(fp_line
			(start -0.2794 -0.1016)
			(end 0.2794 -0.1016)
			(stroke
				(width 0.1)
				(type default)
			)
			(layer "B.Fab")
		)
		(fp_line
			(start 0.2794 -0.1016)
			(end 0.2794 0.9906)
			(stroke
				(width 0.1)
				(type default)
			)
			(layer "B.Fab")
		)
		(pad "1" smd rect
			(at 0 0 90)
			(size 0.508 0.508)
			(layers "B.Cu" "B.Mask" "B.Paste")
			(net "H_CPU1_ERR0_G_N")
		)
		(pad "2" smd rect
			(at 0 0.889 90)
			(size 0.508 0.508)
			(layers "B.Cu" "B.Mask" "B.Paste")
			(net "H_CPU_ERR0_GTL_R_N")
		)
		(zone
			(layer "B.Cu")
			(hatch none 0.5)
			(connect_pads
				(clearance 0)
			)
			(min_thickness 0.25)
			(keepout
				(tracks not_allowed)
				(vias allowed)
				(pads allowed)
				(copperpour not_allowed)
				(footprints allowed)
			)
			(placement
				(enabled no)
				(sheetname "")
			)
			(fill
				(thermal_gap 0.5)
				(thermal_bridge_width 0.5)
				(island_removal_mode 0)
			)
			(polygon
				(pts
					(xy 374.427242 -40.408352) (xy 374.427242 -40.916352) (xy 374.808242 -40.916352) (xy 374.808242 -40.408352)
				)
			)
		)
		(zone
			(layer "B.Cu")
			(hatch none 0.5)
			(connect_pads
				(clearance 0)
			)
			(min_thickness 0.25)
			(keepout
				(tracks allowed)
				(vias not_allowed)
				(pads allowed)
				(copperpour not_allowed)
				(footprints allowed)
			)
			(placement
				(enabled no)
				(sheetname "")
			)
			(fill
				(thermal_gap 0.5)
				(thermal_bridge_width 0.5)
				(island_removal_mode 0)
			)
			(polygon
				(pts
					(xy 374.808242 -40.408352) (xy 374.808242 -40.916352) (xy 374.427242 -40.916352) (xy 374.427242 -40.408352)
				)
			)
		)
	)
)
